# T6G (Grand Teton) — schematic netlist excerpt (pin names and nets, part order shuffled) for the footprints in the layout excerpt that follows; sources: Cadence DE-HDL packaged netlist, KiCad conversion of 04192023_DAF0TMB3IC0_F0TG_MB_C_brd_V02_OCP.brd

C64  Q_CAP  0.1UF 25V 10% EMPTY  pkg 0402  page 240 : A = PDB_PRSNT_N ; B = GND
R729  Q_RES  10K 5% EMPTY  pkg 0402LF  page 76 : A = PVDD18_S5_P0 ; B = UART_CPU0_SCM_UART1_TX

(kicad_pcb
	(version 20260206)
	(generator "pcbnew")
	(generator_version "10.0")
	(general
		(thickness 1.6)
		(legacy_teardrops no)
	)
	(paper "A4")
	(title_block
		(title "04192023_DAF0TMB3IC0_F0TG_MB_C_brd_V02_OCP.brd")
		(comment 1 "Grand Teton / footprints 6674-6675 of 8354")
	)
	(layers
		(0 "F.Cu" signal "TOP")
		(4 "In1.Cu" signal "GND")
		(6 "In2.Cu" signal "IN1")
		(8 "In3.Cu" signal "GND1")
		(10 "In4.Cu" signal "IN2")
		(12 "In5.Cu" signal "GND2")
		(14 "In6.Cu" signal "IN3")
		(16 "In7.Cu" signal "GND3")
		(18 "In8.Cu" signal "VCC")
		(20 "In9.Cu" signal "VCC1")
		(22 "In10.Cu" signal "GND4")
		(24 "In11.Cu" signal "IN4")
		(26 "In12.Cu" signal "GND5")
		(28 "In13.Cu" signal "IN5")
		(30 "In14.Cu" signal "GND6")
		(32 "In15.Cu" signal "IN6")
		(34 "In16.Cu" signal "GND7")
		(2 "B.Cu" signal "BOTTOM")
		(9 "F.Adhes" user "F.Adhesive")
		(11 "B.Adhes" user "B.Adhesive")
		(13 "F.Paste" user "Package Geometry/Pastemask Top")
		(15 "B.Paste" user "Package Geometry/Pastemask Bottom")
		(5 "F.SilkS" user "Ref Des/Silkscreen Top")
		(7 "B.SilkS" user "Ref Des/Silkscreen Bottom")
		(1 "F.Mask" user "Board Geometry/Soldermask Top")
		(3 "B.Mask" user "Board Geometry/Soldermask Bottom")
		(17 "Dwgs.User" user "User.Drawings")
		(19 "Cmts.User" user "User.Comments")
		(21 "Eco1.User" user "User.Eco1")
		(23 "Eco2.User" user "User.Eco2")
		(25 "Edge.Cuts" user "Board Geometry/Outline")
		(27 "Margin" user)
		(31 "F.CrtYd" user "Package Geometry/Place Bound Top")
		(29 "B.CrtYd" user "Package Geometry/Place Bound Bottom")
		(35 "F.Fab" user "Ref Des/Assembly Top")
		(33 "B.Fab" user "Ref Des/Assembly Bottom")
	)
	(footprint ""
		(layer "B.Cu")
		(at 339.134958 -306.828952 180)
		(property "Reference" "R729"
			(at 0 0 0)
			(layer "B.SilkS")
			(hide yes)
			(effects
				(font
					(size 1.27 1.27)
				)
				(justify mirror)
			)
		)
		(property "Value" ""
			(at 0 0 0)
			(layer "B.Fab")
			(effects
				(font
					(size 1.27 1.27)
				)
				(justify mirror)
			)
		)
		(duplicate_pad_numbers_are_jumpers no)
		(fp_line
			(start 0.7874 0.4064)
			(end 0.7874 -0.4064)
			(stroke
				(width 0.1524)
				(type default)
			)
			(layer "B.SilkS")
		)
		(fp_line
			(start 0.7874 -0.4064)
			(end -0.7874 -0.4064)
			(stroke
				(width 0.1524)
				(type default)
			)
			(layer "B.SilkS")
		)
		(fp_line
			(start -0.7874 0.4064)
			(end 0.7874 0.4064)
			(stroke
				(width 0.1524)
				(type default)
			)
			(layer "B.SilkS")
		)
		(fp_line
			(start -0.7874 -0.4064)
			(end -0.7874 0.4064)
			(stroke
				(width 0.1524)
				(type default)
			)
			(layer "B.SilkS")
		)
		(fp_line
			(start 0.67945 0.3048)
			(end 0.67945 -0.305054)
			(stroke
				(width 0.1)
				(type default)
			)
			(layer "B.Fab")
		)
		(fp_line
			(start 0.67945 -0.305054)
			(end 0.12065 -0.305054)
			(stroke
				(width 0.1)
				(type default)
			)
			(layer "B.Fab")
		)
		(fp_line
			(start 0.12065 0.3048)
			(end 0.67945 0.3048)
			(stroke
				(width 0.1)
				(type default)
			)
			(layer "B.Fab")
		)
		(fp_line
			(start 0.12065 0.2794)
			(end 0.12065 0.3048)
			(stroke
				(width 0.1)
				(type default)
			)
			(layer "B.Fab")
		)
		(fp_line
			(start 0.12065 -0.2794)
			(end -0.12065 -0.2794)
			(stroke
				(width 0.1)
				(type default)
			)
			(layer "B.Fab")
		)
		(fp_line
			(start 0.12065 -0.305054)
			(end 0.12065 -0.2794)
			(stroke
				(width 0.1)
				(type default)
			)
			(layer "B.Fab")
		)
		(fp_line
			(start -0.120396 0.3048)
			(end -0.120396 0.2794)
			(stroke
				(width 0.1)
				(type default)
			)
			(layer "B.Fab")
		)
		(fp_line
			(start -0.120396 0.2794)
			(end 0.12065 0.2794)
			(stroke
				(width 0.1)
				(type default)
			)
			(layer "B.Fab")
		)
		(fp_line
			(start -0.12065 -0.2794)
			(end -0.12065 -0.3048)
			(stroke
				(width 0.1)
				(type default)
			)
			(layer "B.Fab")
		)
		(fp_line
			(start -0.12065 -0.3048)
			(end -0.67945 -0.3048)
			(stroke
				(width 0.1)
				(type default)
			)
			(layer "B.Fab")
		)
		(fp_line
			(start -0.67945 0.3048)
			(end -0.120396 0.3048)
			(stroke
				(width 0.1)
				(type default)
			)
			(layer "B.Fab")
		)
		(fp_line
			(start -0.67945 -0.3048)
			(end -0.67945 0.3048)
			(stroke
				(width 0.1)
				(type default)
			)
			(layer "B.Fab")
		)
		(pad "1" smd circle
			(at 0.40005 0)
			(size 0 0)
			(layers "B.Cu" "B.Mask" "B.Paste")
			(net "PVDD18_S5_P0")
		)
		(pad "2" smd circle
			(at -0.40005 0)
			(size 0 0)
			(layers "B.Cu" "B.Mask" "B.Paste")
			(net "UART_CPU0_SCM_UART1_TX")
		)
	)
	(footprint ""
		(layer "B.Cu")
		(at 233.37012 -422.849548 90)
		(property "Reference" "C64"
			(at 0 0 90)
			(layer "B.SilkS")
			(hide yes)
			(effects
				(font
					(size 1.27 1.27)
				)
				(justify mirror)
			)
		)
		(property "Value" ""
			(at 0 0 90)
			(layer "B.Fab")
			(effects
				(font
					(size 1.27 1.27)
				)
				(justify mirror)
			)
		)
		(duplicate_pad_numbers_are_jumpers no)
		(fp_line
			(start 0.7874 -0.4064)
			(end -0.7874 -0.4064)
			(stroke
				(width 0.1524)
				(type default)
			)
			(layer "B.SilkS")
		)
		(fp_line
			(start -0.7874 -0.4064)
			(end -0.7874 0.4064)
			(stroke
				(width 0.1524)
				(type default)
			)
			(layer "B.SilkS")
		)
		(fp_line
			(start 0.7874 0.4064)
			(end 0.7874 -0.4064)
			(stroke
				(width 0.1524)
				(type default)
			)
			(layer "B.SilkS")
		)
		(fp_line
			(start -0.7874 0.4064)
			(end 0.7874 0.4064)
			(stroke
				(width 0.1524)
				(type default)
			)
			(layer "B.SilkS")
		)
		(fp_line
			(start 0.67945 -0.305054)
			(end 0.12065 -0.305054)
			(stroke
				(width 0.1)
				(type default)
			)
			(layer "B.Fab")
		)
		(fp_line
			(start 0.12065 -0.305054)
			(end 0.12065 -0.2794)
			(stroke
				(width 0.1)
				(type default)
			)
			(layer "B.Fab")
		)
		(fp_line
			(start -0.12065 -0.3048)
			(end -0.67945 -0.3048)
			(stroke
				(width 0.1)
				(type default)
			)
			(layer "B.Fab")
		)
		(fp_line
			(start -0.67945 -0.3048)
			(end -0.67945 0.3048)
			(stroke
				(width 0.1)
				(type default)
			)
			(layer "B.Fab")
		)
		(fp_line
			(start 0.12065 -0.2794)
			(end -0.12065 -0.2794)
			(stroke
				(width 0.1)
				(type default)
			)
			(layer "B.Fab")
		)
		(fp_line
			(start -0.12065 -0.2794)
			(end -0.12065 -0.3048)
			(stroke
				(width 0.1)
				(type default)
			)
			(layer "B.Fab")
		)
		(fp_line
			(start 0.12065 0.2794)
			(end 0.12065 0.3048)
			(stroke
				(width 0.1)
				(type default)
			)
			(layer "B.Fab")
		)
		(fp_line
			(start -0.120396 0.2794)
			(end 0.12065 0.2794)
			(stroke
				(width 0.1)
				(type default)
			)
			(layer "B.Fab")
		)
		(fp_line
			(start 0.67945 0.3048)
			(end 0.67945 -0.305054)
			(stroke
				(width 0.1)
				(type default)
			)
			(layer "B.Fab")
		)
		(fp_line
			(start 0.12065 0.3048)
			(end 0.67945 0.3048)
			(stroke
				(width 0.1)
				(type default)
			)
			(layer "B.Fab")
		)
		(fp_line
			(start -0.120396 0.3048)
			(end -0.120396 0.2794)
			(stroke
				(width 0.1)
				(type default)
			)
			(layer "B.Fab")
		)
		(fp_line
			(start -0.67945 0.3048)
			(end -0.120396 0.3048)
			(stroke
				(width 0.1)
				(type default)
			)
			(layer "B.Fab")
		)
		(pad "1" smd circle
			(at 0.40005 0 270)
			(size 0 0)
			(layers "B.Cu" "B.Mask" "B.Paste")
			(net "PDB_PRSNT_N")
		)
		(pad "2" smd circle
			(at -0.40005 0 270)
			(size 0 0)
			(layers "B.Cu" "B.Mask" "B.Paste")
			(net "GND")
		)
	)
)
